(kicad_pcb
	(version 20260206)
	(generator "pcbnew")
	(generator_version "10.0")
	(general
		(thickness 1.6)
		(legacy_teardrops no)
	)
	(paper "A4")
	(title_block
		(title "Wiwynn_Tioga_Pass_MB.brd")
		(comment 1 "Tioga Pass / footprints 2168-2174 of 4770")
	)
	(layers
		(0 "F.Cu" signal "TOP")
		(4 "In1.Cu" signal "L2GND")
		(6 "In2.Cu" signal "L3")
		(8 "In3.Cu" signal "L4GND")
		(10 "In4.Cu" signal "L5")
		(12 "In5.Cu" signal "L6GND")
		(14 "In6.Cu" signal "L7VCC")
		(16 "In7.Cu" signal "L8VCC")
		(18 "In8.Cu" signal "L9GND")
		(20 "In9.Cu" signal "L10")
		(22 "In10.Cu" signal "L11GND")
		(24 "In11.Cu" signal "L12")
		(26 "In12.Cu" signal "L13GND")
		(2 "B.Cu" signal "BOTTOM")
		(9 "F.Adhes" user "F.Adhesive")
		(11 "B.Adhes" user "B.Adhesive")
		(13 "F.Paste" user "Package Geometry/Pastemask Top")
		(15 "B.Paste" user "Package Geometry/Pastemask Bottom")
		(5 "F.SilkS" user "Ref Des/Silkscreen Top")
		(7 "B.SilkS" user "Ref Des/Silkscreen Bottom")
		(1 "F.Mask" user "Board Geometry/Soldermask Top")
		(3 "B.Mask" user "Board Geometry/Soldermask Bottom")
		(17 "Dwgs.User" user "User.Drawings")
		(19 "Cmts.User" user "User.Comments")
		(21 "Eco1.User" user "User.Eco1")
		(23 "Eco2.User" user "User.Eco2")
		(25 "Edge.Cuts" user "Board Geometry/Outline")
		(27 "Margin" user)
		(31 "F.CrtYd" user "Package Geometry/Place Bound Top")
		(29 "B.CrtYd" user "Package Geometry/Place Bound Bottom")
		(35 "F.Fab" user "Ref Des/Assembly Top")
		(33 "B.Fab" user "Ref Des/Assembly Bottom")
	)
	(footprint ""
		(layer "F.Cu")
		(at 354.27412 -98.730054 90)
		(property "Reference" "CT71"
			(at -0.53467 1.8288 0)
			(unlocked yes)
			(layer "F.SilkS")
			(effects
				(font
					(size 0.7874 0.5842)
					(thickness 0.1524)
				)
				(justify left)
			)
		)
		(property "Value" ""
			(at 0 0 90)
			(layer "F.Fab")
			(effects
				(font
					(size 1.27 1.27)
				)
			)
		)
		(duplicate_pad_numbers_are_jumpers no)
		(fp_poly
			(pts
				(xy 0.3048 -0.1016) (xy 0.3048 0.9906) (xy -0.3048 0.9906) (xy -0.3048 -0.1016)
			)
			(stroke
				(width 0)
				(type default)
			)
			(fill no)
			(layer "F.CrtYd")
		)
		(fp_line
			(start 0.3048 -0.1016)
			(end -0.3048 -0.1016)
			(stroke
				(width 0.1)
				(type default)
			)
			(layer "F.Fab")
		)
		(fp_line
			(start -0.3048 -0.1016)
			(end -0.3048 0.9906)
			(stroke
				(width 0.1)
				(type default)
			)
			(layer "F.Fab")
		)
		(fp_line
			(start 0.3048 0.9906)
			(end 0.3048 -0.1016)
			(stroke
				(width 0.1)
				(type default)
			)
			(layer "F.Fab")
		)
		(fp_line
			(start -0.3048 0.9906)
			(end 0.3048 0.9906)
			(stroke
				(width 0.1)
				(type default)
			)
			(layer "F.Fab")
		)
		(pad "1" smd rect
			(at 0 0 90)
			(size 0.508 0.508)
			(layers "F.Cu" "F.Mask" "F.Paste")
			(net "A_TSENSE_PVCCIO_CPU0")
		)
		(pad "2" smd rect
			(at 0 0.889 90)
			(size 0.508 0.508)
			(layers "F.Cu" "F.Mask" "F.Paste")
			(net "GND")
		)
		(zone
			(layer "F.Cu")
			(hatch none 0.5)
			(connect_pads
				(clearance 0)
			)
			(min_thickness 0.25)
			(keepout
				(tracks allowed)
				(vias not_allowed)
				(pads allowed)
				(copperpour not_allowed)
				(footprints allowed)
			)
			(placement
				(enabled no)
				(sheetname "")
			)
			(fill
				(thermal_gap 0.5)
				(thermal_bridge_width 0.5)
				(island_removal_mode 0)
			)
			(polygon
				(pts
					(xy 354.52812 -98.476054) (xy 354.52812 -98.984054) (xy 354.90912 -98.984054) (xy 354.90912 -98.476054)
				)
			)
		)
		(zone
			(layer "F.Cu")
			(hatch none 0.5)
			(connect_pads
				(clearance 0)
			)
			(min_thickness 0.25)
			(keepout
				(tracks not_allowed)
				(vias allowed)
				(pads allowed)
				(copperpour not_allowed)
				(footprints allowed)
			)
			(placement
				(enabled no)
				(sheetname "")
			)
			(fill
				(thermal_gap 0.5)
				(thermal_bridge_width 0.5)
				(island_removal_mode 0)
			)
			(polygon
				(pts
					(xy 354.90912 -98.476054) (xy 354.90912 -98.984054) (xy 354.52812 -98.984054) (xy 354.52812 -98.476054)
				)
			)
		)
	)
	(footprint ""
		(layer "F.Cu")
		(at 412.4452 -115.230402 90)
		(property "Reference" "R2M8"
			(at 0 0 90)
			(layer "F.SilkS")
			(hide yes)
			(effects
				(font
					(size 1.27 1.27)
				)
			)
		)
		(property "Value" ""
			(at 0 0 90)
			(layer "F.Fab")
			(effects
				(font
					(size 1.27 1.27)
				)
			)
		)
		(duplicate_pad_numbers_are_jumpers no)
		(fp_poly
			(pts
				(xy -0.2794 -0.1016) (xy 0.2794 -0.1016) (xy 0.2794 0.9906) (xy -0.2794 0.9906)
			)
			(stroke
				(width 0)
				(type default)
			)
			(fill no)
			(layer "F.CrtYd")
		)
		(fp_line
			(start 0.2794 -0.1016)
			(end -0.2794 -0.1016)
			(stroke
				(width 0.1)
				(type default)
			)
			(layer "F.Fab")
		)
		(fp_line
			(start -0.2794 -0.1016)
			(end -0.2794 0.9906)
			(stroke
				(width 0.1)
				(type default)
			)
			(layer "F.Fab")
		)
		(fp_line
			(start 0.2794 0.9906)
			(end 0.2794 -0.1016)
			(stroke
				(width 0.1)
				(type default)
			)
			(layer "F.Fab")
		)
		(fp_line
			(start -0.2794 0.9906)
			(end 0.2794 0.9906)
			(stroke
				(width 0.1)
				(type default)
			)
			(layer "F.Fab")
		)
		(pad "1" smd rect
			(at 0 0 90)
			(size 0.508 0.508)
			(layers "F.Cu" "F.Mask" "F.Paste")
			(net "P3V3_STBY")
		)
		(pad "2" smd rect
			(at 0 0.889 90)
			(size 0.508 0.508)
			(layers "F.Cu" "F.Mask" "F.Paste")
			(net "FM_CPU0_RC_ERROR_N")
		)
		(zone
			(layer "F.Cu")
			(hatch none 0.5)
			(connect_pads
				(clearance 0)
			)
			(min_thickness 0.25)
			(keepout
				(tracks allowed)
				(vias not_allowed)
				(pads allowed)
				(copperpour not_allowed)
				(footprints allowed)
			)
			(placement
				(enabled no)
				(sheetname "")
			)
			(fill
				(thermal_gap 0.5)
				(thermal_bridge_width 0.5)
				(island_removal_mode 0)
			)
			(polygon
				(pts
					(xy 412.6992 -114.976402) (xy 412.6992 -115.484402) (xy 413.0802 -115.484402) (xy 413.0802 -114.976402)
				)
			)
		)
		(zone
			(layer "F.Cu")
			(hatch none 0.5)
			(connect_pads
				(clearance 0)
			)
			(min_thickness 0.25)
			(keepout
				(tracks not_allowed)
				(vias allowed)
				(pads allowed)
				(copperpour not_allowed)
				(footprints allowed)
			)
			(placement
				(enabled no)
				(sheetname "")
			)
			(fill
				(thermal_gap 0.5)
				(thermal_bridge_width 0.5)
				(island_removal_mode 0)
			)
			(polygon
				(pts
					(xy 413.0802 -114.976402) (xy 413.0802 -115.484402) (xy 412.6992 -115.484402) (xy 412.6992 -114.976402)
				)
			)
		)
	)
	(footprint ""
		(layer "F.Cu")
		(at 24.6888 -66.6242 -90)
		(property "Reference" "R1D48"
			(at 0 0 270)
			(layer "F.SilkS")
			(hide yes)
			(effects
				(font
					(size 1.27 1.27)
				)
			)
		)
		(property "Value" ""
			(at 0 0 270)
			(layer "F.Fab")
			(effects
				(font
					(size 1.27 1.27)
				)
			)
		)
		(duplicate_pad_numbers_are_jumpers no)
		(fp_rect
			(start 0.2794 -0.1016)
			(end -0.2794 0.9906)
			(stroke
				(width 0)
				(type default)
			)
			(fill no)
			(layer "F.CrtYd")
		)
		(fp_line
			(start -0.2794 0.9906)
			(end 0.2794 0.9906)
			(stroke
				(width 0.1)
				(type default)
			)
			(layer "F.Fab")
		)
		(fp_line
			(start 0.2794 0.9906)
			(end 0.2794 -0.1016)
			(stroke
				(width 0.1)
				(type default)
			)
			(layer "F.Fab")
		)
		(fp_line
			(start -0.2794 -0.1016)
			(end -0.2794 0.9906)
			(stroke
				(width 0.1)
				(type default)
			)
			(layer "F.Fab")
		)
		(fp_line
			(start 0.2794 -0.1016)
			(end -0.2794 -0.1016)
			(stroke
				(width 0.1)
				(type default)
			)
			(layer "F.Fab")
		)
		(pad "1" smd rect
			(at 0 0 270)
			(size 0.508 0.508)
			(layers "F.Cu" "F.Mask" "F.Paste")
			(net "A_HSC_GATE")
		)
		(pad "2" smd rect
			(at 0 0.889 270)
			(size 0.508 0.508)
			(layers "F.Cu" "F.Mask" "F.Paste")
			(net "A_HSC_GATE3_R")
		)
		(zone
			(layer "F.Cu")
			(hatch none 0.5)
			(connect_pads
				(clearance 0)
			)
			(min_thickness 0.25)
			(keepout
				(tracks allowed)
				(vias not_allowed)
				(pads allowed)
				(copperpour not_allowed)
				(footprints allowed)
			)
			(placement
				(enabled no)
				(sheetname "")
			)
			(fill
				(thermal_gap 0.5)
				(thermal_bridge_width 0.5)
				(island_removal_mode 0)
			)
			(polygon
				(pts
					(xy 24.4348 -66.3702) (xy 24.4348 -66.8782) (xy 24.0538 -66.8782) (xy 24.0538 -66.3702)
				)
			)
		)
		(zone
			(layer "F.Cu")
			(hatch none 0.5)
			(connect_pads
				(clearance 0)
			)
			(min_thickness 0.25)
			(keepout
				(tracks not_allowed)
				(vias allowed)
				(pads allowed)
				(copperpour not_allowed)
				(footprints allowed)
			)
			(placement
				(enabled no)
				(sheetname "")
			)
			(fill
				(thermal_gap 0.5)
				(thermal_bridge_width 0.5)
				(island_removal_mode 0)
			)
			(polygon
				(pts
					(xy 24.4348 -66.3702) (xy 24.4348 -66.8782) (xy 24.0538 -66.8782) (xy 24.0538 -66.3702)
				)
			)
		)
	)
	(footprint ""
		(layer "F.Cu")
		(at 374.015 -88.2015)
		(property "Reference" "R2R11"
			(at 0 0 0)
			(layer "F.SilkS")
			(hide yes)
			(effects
				(font
					(size 1.27 1.27)
				)
			)
		)
		(property "Value" ""
			(at 0 0 0)
			(layer "F.Fab")
			(effects
				(font
					(size 1.27 1.27)
				)
			)
		)
		(duplicate_pad_numbers_are_jumpers no)
		(fp_poly
			(pts
				(xy -0.2794 -0.1016) (xy 0.2794 -0.1016) (xy 0.2794 0.9906) (xy -0.2794 0.9906)
			)
			(stroke
				(width 0)
				(type default)
			)
			(fill no)
			(layer "F.CrtYd")
		)
		(fp_line
			(start -0.2794 -0.1016)
			(end -0.2794 0.9906)
			(stroke
				(width 0.1)
				(type default)
			)
			(layer "F.Fab")
		)
		(fp_line
			(start -0.2794 0.9906)
			(end 0.2794 0.9906)
			(stroke
				(width 0.1)
				(type default)
			)
			(layer "F.Fab")
		)
		(fp_line
			(start 0.2794 -0.1016)
			(end -0.2794 -0.1016)
			(stroke
				(width 0.1)
				(type default)
			)
			(layer "F.Fab")
		)
		(fp_line
			(start 0.2794 0.9906)
			(end 0.2794 -0.1016)
			(stroke
				(width 0.1)
				(type default)
			)
			(layer "F.Fab")
		)
		(pad "1" smd rect
			(at 0 0)
			(size 0.508 0.508)
			(layers "F.Cu" "F.Mask" "F.Paste")
			(net "SPI_PCH_IO2")
		)
		(pad "2" smd rect
			(at 0 0.889)
			(size 0.508 0.508)
			(layers "F.Cu" "F.Mask" "F.Paste")
			(net "GND")
		)
		(zone
			(layer "F.Cu")
			(hatch none 0.5)
			(connect_pads
				(clearance 0)
			)
			(min_thickness 0.25)
			(keepout
				(tracks allowed)
				(vias not_allowed)
				(pads allowed)
				(copperpour not_allowed)
				(footprints allowed)
			)
			(placement
				(enabled no)
				(sheetname "")
			)
			(fill
				(thermal_gap 0.5)
				(thermal_bridge_width 0.5)
				(island_removal_mode 0)
			)
			(polygon
				(pts
					(xy 373.761 -87.9475) (xy 374.269 -87.9475) (xy 374.269 -87.5665) (xy 373.761 -87.5665)
				)
			)
		)
		(zone
			(layer "F.Cu")
			(hatch none 0.5)
			(connect_pads
				(clearance 0)
			)
			(min_thickness 0.25)
			(keepout
				(tracks not_allowed)
				(vias allowed)
				(pads allowed)
				(copperpour not_allowed)
				(footprints allowed)
			)
			(placement
				(enabled no)
				(sheetname "")
			)
			(fill
				(thermal_gap 0.5)
				(thermal_bridge_width 0.5)
				(island_removal_mode 0)
			)
			(polygon
				(pts
					(xy 373.761 -87.5665) (xy 374.269 -87.5665) (xy 374.269 -87.9475) (xy 373.761 -87.9475)
				)
			)
		)
	)
	(footprint ""
		(layer "F.Cu")
		(at 2.794 -69.088 180)
		(property "Reference" "R1E9"
			(at 0 0 180)
			(layer "F.SilkS")
			(hide yes)
			(effects
				(font
					(size 1.27 1.27)
				)
			)
		)
		(property "Value" ""
			(at 0 0 180)
			(layer "F.Fab")
			(effects
				(font
					(size 1.27 1.27)
				)
			)
		)
		(duplicate_pad_numbers_are_jumpers no)
		(fp_poly
			(pts
				(xy -0.2794 -0.1016) (xy 0.2794 -0.1016) (xy 0.2794 0.9906) (xy -0.2794 0.9906)
			)
			(stroke
				(width 0)
				(type default)
			)
			(fill no)
			(layer "F.CrtYd")
		)
		(fp_line
			(start 0.2794 0.9906)
			(end 0.2794 -0.1016)
			(stroke
				(width 0.1)
				(type default)
			)
			(layer "F.Fab")
		)
		(fp_line
			(start 0.2794 -0.1016)
			(end -0.2794 -0.1016)
			(stroke
				(width 0.1)
				(type default)
			)
			(layer "F.Fab")
		)
		(fp_line
			(start -0.2794 0.9906)
			(end 0.2794 0.9906)
			(stroke
				(width 0.1)
				(type default)
			)
			(layer "F.Fab")
		)
		(fp_line
			(start -0.2794 -0.1016)
			(end -0.2794 0.9906)
			(stroke
				(width 0.1)
				(type default)
			)
			(layer "F.Fab")
		)
		(pad "1" smd rect
			(at 0 0 180)
			(size 0.508 0.508)
			(layers "F.Cu" "F.Mask" "F.Paste")
			(net "P3V3_STBY")
		)
		(pad "2" smd rect
			(at 0 0.889 180)
			(size 0.508 0.508)
			(layers "F.Cu" "F.Mask" "F.Paste")
			(net "PU_TMP421_2_A0")
		)
		(zone
			(layer "F.Cu")
			(hatch none 0.5)
			(connect_pads
				(clearance 0)
			)
			(min_thickness 0.25)
			(keepout
				(tracks not_allowed)
				(vias allowed)
				(pads allowed)
				(copperpour not_allowed)
				(footprints allowed)
			)
			(placement
				(enabled no)
				(sheetname "")
			)
			(fill
				(thermal_gap 0.5)
				(thermal_bridge_width 0.5)
				(island_removal_mode 0)
			)
			(polygon
				(pts
					(xy 3.048 -69.723) (xy 2.54 -69.723) (xy 2.54 -69.342) (xy 3.048 -69.342)
				)
			)
		)
		(zone
			(layer "F.Cu")
			(hatch none 0.5)
			(connect_pads
				(clearance 0)
			)
			(min_thickness 0.25)
			(keepout
				(tracks allowed)
				(vias not_allowed)
				(pads allowed)
				(copperpour not_allowed)
				(footprints allowed)
			)
			(placement
				(enabled no)
				(sheetname "")
			)
			(fill
				(thermal_gap 0.5)
				(thermal_bridge_width 0.5)
				(island_removal_mode 0)
			)
			(polygon
				(pts
					(xy 3.048 -69.342) (xy 2.54 -69.342) (xy 2.54 -69.723) (xy 3.048 -69.723)
				)
			)
		)
	)
	(footprint ""
		(layer "F.Cu")
		(at 422.744646 -48.968152)
		(property "Reference" "R25W102"
			(at -0.8382 -0.67818 0)
			(unlocked yes)
			(layer "F.SilkS")
			(effects
				(font
					(size 0.4064 0.254)
					(thickness 0.1524)
				)
				(justify left)
			)
		)
		(property "Value" ""
			(at 0 0 0)
			(layer "F.Fab")
			(effects
				(font
					(size 1.27 1.27)
				)
			)
		)
		(duplicate_pad_numbers_are_jumpers no)
		(fp_poly
			(pts
				(xy -0.2794 -0.1016) (xy 0.2794 -0.1016) (xy 0.2794 0.9906) (xy -0.2794 0.9906)
			)
			(stroke
				(width 0)
				(type default)
			)
			(fill no)
			(layer "F.CrtYd")
		)
		(fp_line
			(start -0.2794 -0.1016)
			(end -0.2794 0.9906)
			(stroke
				(width 0.1)
				(type default)
			)
			(layer "F.Fab")
		)
		(fp_line
			(start -0.2794 0.9906)
			(end 0.2794 0.9906)
			(stroke
				(width 0.1)
				(type default)
			)
			(layer "F.Fab")
		)
		(fp_line
			(start 0.2794 -0.1016)
			(end -0.2794 -0.1016)
			(stroke
				(width 0.1)
				(type default)
			)
			(layer "F.Fab")
		)
		(fp_line
			(start 0.2794 0.9906)
			(end 0.2794 -0.1016)
			(stroke
				(width 0.1)
				(type default)
			)
			(layer "F.Fab")
		)
		(pad "1" smd rect
			(at 0 0)
			(size 0.508 0.508)
			(layers "F.Cu" "F.Mask" "F.Paste")
			(net "P3V3_STBY")
		)
		(pad "2" smd rect
			(at 0 0.889)
			(size 0.508 0.508)
			(layers "F.Cu" "F.Mask" "F.Paste")
			(net "BMC_STRAP_BIT18")
		)
		(zone
			(layer "F.Cu")
			(hatch none 0.5)
			(connect_pads
				(clearance 0)
			)
			(min_thickness 0.25)
			(keepout
				(tracks allowed)
				(vias not_allowed)
				(pads allowed)
				(copperpour not_allowed)
				(footprints allowed)
			)
			(placement
				(enabled no)
				(sheetname "")
			)
			(fill
				(thermal_gap 0.5)
				(thermal_bridge_width 0.5)
				(island_removal_mode 0)
			)
			(polygon
				(pts
					(xy 422.490646 -48.714152) (xy 422.998646 -48.714152) (xy 422.998646 -48.333152) (xy 422.490646 -48.333152)
				)
			)
		)
		(zone
			(layer "F.Cu")
			(hatch none 0.5)
			(connect_pads
				(clearance 0)
			)
			(min_thickness 0.25)
			(keepout
				(tracks not_allowed)
				(vias allowed)
				(pads allowed)
				(copperpour not_allowed)
				(footprints allowed)
			)
			(placement
				(enabled no)
				(sheetname "")
			)
			(fill
				(thermal_gap 0.5)
				(thermal_bridge_width 0.5)
				(island_removal_mode 0)
			)
			(polygon
				(pts
					(xy 422.490646 -48.333152) (xy 422.998646 -48.333152) (xy 422.998646 -48.714152) (xy 422.490646 -48.714152)
				)
			)
		)
	)
	(footprint ""
		(layer "F.Cu")
		(at 25.521158 -102.40772 -90)
		(property "Reference" "C1C2"
			(at 4.445 -1.55067 90)
			(unlocked yes)
			(layer "F.SilkS")
			(effects
				(font
					(size 0.7874 0.5842)
					(thickness 0.1524)
				)
				(justify left)
			)
		)
		(property "Value" ""
			(at 0 0 270)
			(layer "F.Fab")
			(effects
				(font
					(size 1.27 1.27)
				)
			)
		)
		(duplicate_pad_numbers_are_jumpers no)
		(fp_line
			(start -3.400044 6.067044)
			(end -0.9017 6.067044)
			(stroke
				(width 0.1524)
				(type default)
			)
			(layer "F.SilkS")
		)
		(fp_line
			(start 0.9017 6.067044)
			(end 3.400044 6.067044)
			(stroke
				(width 0.1524)
				(type default)
			)
			(layer "F.SilkS")
		)
		(fp_line
			(start 3.400044 6.067044)
			(end 3.400044 0.028956)
			(stroke
				(width 0.1524)
				(type default)
			)
			(layer "F.SilkS")
		)
		(fp_line
			(start -0.9017 1.587754)
			(end -0.7239 1.587754)
			(stroke
				(width 0.1524)
				(type default)
			)
			(layer "F.SilkS")
		)
		(fp_line
			(start 0.7239 1.587754)
			(end 0.9017 1.587754)
			(stroke
				(width 0.1524)
				(type default)
			)
			(layer "F.SilkS")
		)
		(fp_line
			(start 0.9017 1.587754)
			(end 0.9017 -1.714246)
			(stroke
				(width 0.1524)
				(type default)
			)
			(layer "F.SilkS")
		)
		(fp_line
			(start -3.400044 0.028956)
			(end -3.400044 6.067044)
			(stroke
				(width 0.1524)
				(type default)
			)
			(layer "F.SilkS")
		)
		(fp_line
			(start 3.400044 0.028956)
			(end 2.638044 -0.733044)
			(stroke
				(width 0.1524)
				(type default)
			)
			(layer "F.SilkS")
		)
		(fp_line
			(start -2.638044 -0.733044)
			(end -3.400044 0.028956)
			(stroke
				(width 0.1524)
				(type default)
			)
			(layer "F.SilkS")
		)
		(fp_line
			(start -0.9017 -0.733044)
			(end -2.638044 -0.733044)
			(stroke
				(width 0.1524)
				(type default)
			)
			(layer "F.SilkS")
		)
		(fp_line
			(start 2.638044 -0.733044)
			(end 0.9017 -0.733044)
			(stroke
				(width 0.1524)
				(type default)
			)
			(layer "F.SilkS")
		)
		(fp_line
			(start -0.9017 -1.714246)
			(end -0.9017 1.587754)
			(stroke
				(width 0.1524)
				(type default)
			)
			(layer "F.SilkS")
		)
		(fp_line
			(start -0.7239 -1.714246)
			(end -0.9017 -1.714246)
			(stroke
				(width 0.1524)
				(type default)
			)
			(layer "F.SilkS")
		)
		(fp_line
			(start 0.9017 -1.714246)
			(end 0.7239 -1.714246)
			(stroke
				(width 0.1524)
				(type default)
			)
			(layer "F.SilkS")
		)
		(fp_poly
			(pts
				(xy -3.400044 6.067044) (xy 3.400044 6.067044) (xy 3.400044 0.028956) (xy 2.638044 -0.733044) (xy -2.638044 -0.733044)
				(xy -3.400044 0.028956)
			)
			(stroke
				(width 0)
				(type default)
			)
			(fill no)
			(layer "F.CrtYd")
		)
		(fp_line
			(start -3.400044 6.067044)
			(end 3.400044 6.067044)
			(stroke
				(width 0.1)
				(type default)
			)
			(layer "F.Fab")
		)
		(fp_line
			(start 3.400044 6.067044)
			(end 3.400044 0.028956)
			(stroke
				(width 0.1)
				(type default)
			)
			(layer "F.Fab")
		)
		(fp_line
			(start -3.400044 0.028956)
			(end -3.400044 6.067044)
			(stroke
				(width 0.1)
				(type default)
			)
			(layer "F.Fab")
		)
		(fp_line
			(start 3.400044 0.028956)
			(end 2.638044 -0.733044)
			(stroke
				(width 0.1)
				(type default)
			)
			(layer "F.Fab")
		)
		(fp_line
			(start -2.638044 -0.733044)
			(end -3.400044 0.028956)
			(stroke
				(width 0.1)
				(type default)
			)
			(layer "F.Fab")
		)
		(fp_line
			(start 2.638044 -0.733044)
			(end -2.638044 -0.733044)
			(stroke
				(width 0.1)
				(type default)
			)
			(layer "F.Fab")
		)
		(fp_circle
			(center 0 2.667)
			(end 0 -0.733044)
			(stroke
				(width 0.1)
				(type default)
			)
			(fill no)
			(layer "F.Fab")
		)
		(pad "1" smd rect
			(at 0 0 270)
			(size 0.7874 3.429)
			(layers "F.Cu" "F.Mask" "F.Paste")
			(net "VR_FET_SW_P12V_STBY_PVCCIN_CPU1")
		)
		(pad "2" smd rect
			(at 0 5.334 270)
			(size 0.7874 3.429)
			(layers "F.Cu" "F.Mask" "F.Paste")
			(net "GND")
		)
	)
)
